(kicad_pcb
	(version 20241229)
	(generator "pcbnew")
	(generator_version "9.0")
	(general
		(thickness 1.62)
		(legacy_teardrops no)
	)
	(paper "A4")
	(title_block
		(title "OCuLink to 10GbE adapter")
		(date "2026-02-23")
		(rev "1.1.0")
		(company "Antmicro Ltd")
		(comment 1 "www.antmicro.com")
		(comment 9 "footprints 345-350 of 510")
	)
	(layers
		(0 "F.Cu" signal)
		(4 "In1.Cu" signal)
		(6 "In2.Cu" signal)
		(8 "In3.Cu" signal)
		(10 "In4.Cu" signal)
		(12 "In5.Cu" signal)
		(14 "In6.Cu" signal)
		(2 "B.Cu" signal)
		(9 "F.Adhes" user "F.Adhesive")
		(11 "B.Adhes" user "B.Adhesive")
		(13 "F.Paste" user)
		(15 "B.Paste" user)
		(5 "F.SilkS" user "F.Silkscreen")
		(7 "B.SilkS" user "B.Silkscreen")
		(1 "F.Mask" user)
		(3 "B.Mask" user)
		(17 "Dwgs.User" user "User.Drawings")
		(19 "Cmts.User" user "User.Comments")
		(21 "Eco1.User" user "User.Eco1")
		(23 "Eco2.User" user "User.Eco2")
		(25 "Edge.Cuts" user)
		(27 "Margin" user)
		(31 "F.CrtYd" user "F.Courtyard")
		(29 "B.CrtYd" user "B.Courtyard")
		(35 "F.Fab" user)
		(33 "B.Fab" user)
	)
	(footprint "antmicro-footprints:R_0402_1005Metric"
		(layer "B.Cu")
		(at 100.62 88.734 -90)
		(descr "Resistor SMD 0402")
		(tags "resistor SMD 0402")
		(property "Reference" "R125"
			(at -0.834 -0.48 90)
			(layer "B.SilkS")
			(effects
				(font
					(size 0.7 0.7)
					(thickness 0.15)
				)
				(justify right bottom mirror)
			)
		)
		(property "Value" "R_49R9_0402"
			(at -1.011843 -1.772047 90)
			(layer "B.Fab")
			(hide yes)
			(effects
				(font
					(size 0.7 0.7)
					(thickness 0.15)
				)
				(justify left bottom mirror)
			)
		)
		(property "Datasheet" "https://www.bourns.com/docs/product-datasheets/cr.pdf"
			(at 0 0 90)
			(layer "B.Fab")
			(hide yes)
			(effects
				(font
					(size 1.27 1.27)
					(thickness 0.15)
				)
				(justify mirror)
			)
		)
		(property "Description" "SMD Chip Resistor, 49.9 ohm, ± 1%, 62.5 mW, 0402 [1005 Metric], Thick Film, General Purpose"
			(at 0 0 90)
			(layer "B.Fab")
			(hide yes)
			(effects
				(font
					(size 1.27 1.27)
					(thickness 0.15)
				)
				(justify mirror)
			)
		)
		(property "MPN" "CR0402-FX-49R9GLF"
			(at 0 0 90)
			(unlocked yes)
			(layer "B.Fab")
			(hide yes)
			(effects
				(font
					(size 1 1)
					(thickness 0.15)
				)
				(justify mirror)
			)
		)
		(property "Manufacturer" "Bourns"
			(at 0 0 90)
			(unlocked yes)
			(layer "B.Fab")
			(hide yes)
			(effects
				(font
					(size 1 1)
					(thickness 0.15)
				)
				(justify mirror)
			)
		)
		(property "License" "Apache-2.0"
			(at 0 0 90)
			(unlocked yes)
			(layer "B.Fab")
			(hide yes)
			(effects
				(font
					(size 1 1)
					(thickness 0.15)
				)
				(justify mirror)
			)
		)
		(property "Author" "Antmicro"
			(at 0 0 90)
			(unlocked yes)
			(layer "B.Fab")
			(hide yes)
			(effects
				(font
					(size 1 1)
					(thickness 0.15)
				)
				(justify mirror)
			)
		)
		(property "Val" "49R9"
			(at 0 0 90)
			(unlocked yes)
			(layer "B.Fab")
			(hide yes)
			(effects
				(font
					(size 1 1)
					(thickness 0.15)
				)
				(justify mirror)
			)
		)
		(property "Tolerance" "1%"
			(at 0 0 90)
			(unlocked yes)
			(layer "B.Fab")
			(hide yes)
			(effects
				(font
					(size 1 1)
					(thickness 0.15)
				)
				(justify mirror)
			)
		)
		(sheetname "/X710-AT2 PCIe/")
		(sheetfile "x710-at2-pcie.kicad_sch")
		(attr smd exclude_from_pos_files exclude_from_bom dnp)
		(fp_rect
			(start -0.925 0.47)
			(end 0.925 -0.47)
			(stroke
				(width 0.05)
				(type default)
			)
			(fill no)
			(layer "B.CrtYd")
		)
		(fp_rect
			(start -0.5 0.25)
			(end 0.5 -0.25)
			(stroke
				(width 0.15)
				(type solid)
			)
			(fill no)
			(layer "B.Fab")
		)
		(pad "1" smd roundrect
			(at -0.48 0 270)
			(size 0.59 0.64)
			(layers "B.Cu" "B.Mask" "B.Paste")
			(roundrect_rratio 0.25)
			(net 28 "GND")
			(pintype "passive")
		)
		(pad "2" smd roundrect
			(at 0.48 0 270)
			(size 0.59 0.64)
			(layers "B.Cu" "B.Mask" "B.Paste")
			(roundrect_rratio 0.25)
			(net 406 "/X710-AT2 PCIe/GEN_F_CLK-")
			(pintype "passive")
		)
	)
	(footprint "antmicro-footprints:R_0402_1005Metric"
		(layer "B.Cu")
		(at 96.45 99.1)
		(descr "Resistor SMD 0402")
		(tags "resistor SMD 0402")
		(property "Reference" "R64"
			(at 0.9 -0.338889 0)
			(layer "B.SilkS")
			(effects
				(font
					(size 0.7 0.7)
					(thickness 0.15)
				)
				(justify right top mirror)
			)
		)
		(property "Value" "R_3k3_0402"
			(at -1.011843 -1.772046 0)
			(layer "B.Fab")
			(hide yes)
			(effects
				(font
					(size 0.7 0.7)
					(thickness 0.15)
				)
				(justify right top mirror)
			)
		)
		(property "Datasheet" "https://www.bourns.com/docs/product-datasheets/cr.pdf"
			(at 0 0 0)
			(layer "B.Fab")
			(hide yes)
			(effects
				(font
					(size 1.27 1.27)
					(thickness 0.15)
				)
				(justify mirror)
			)
		)
		(property "Description" "SMD Chip Resistor, 3.3 kohm, ± 1%, 63 mW, 0402 [1005 Metric], Thick Film, General Purpose"
			(at 0 0 0)
			(layer "B.Fab")
			(hide yes)
			(effects
				(font
					(size 1.27 1.27)
					(thickness 0.15)
				)
				(justify mirror)
			)
		)
		(property "MPN" "CR0402-FX-3301GLF"
			(at 0 0 0)
			(unlocked yes)
			(layer "B.Fab")
			(hide yes)
			(effects
				(font
					(size 1 1)
					(thickness 0.15)
				)
				(justify mirror)
			)
		)
		(property "Manufacturer" "Bourns"
			(at 0 0 0)
			(unlocked yes)
			(layer "B.Fab")
			(hide yes)
			(effects
				(font
					(size 1 1)
					(thickness 0.15)
				)
				(justify mirror)
			)
		)
		(property "License" "Apache-2.0"
			(at 0 0 0)
			(unlocked yes)
			(layer "B.Fab")
			(hide yes)
			(effects
				(font
					(size 1 1)
					(thickness 0.15)
				)
				(justify mirror)
			)
		)
		(property "Author" "Antmicro"
			(at 0 0 0)
			(unlocked yes)
			(layer "B.Fab")
			(hide yes)
			(effects
				(font
					(size 1 1)
					(thickness 0.15)
				)
				(justify mirror)
			)
		)
		(property "Val" "3k3"
			(at 0 0 0)
			(unlocked yes)
			(layer "B.Fab")
			(hide yes)
			(effects
				(font
					(size 1 1)
					(thickness 0.15)
				)
				(justify mirror)
			)
		)
		(property "Tolerance" "1%"
			(at 0 0 0)
			(unlocked yes)
			(layer "B.Fab")
			(hide yes)
			(effects
				(font
					(size 1 1)
					(thickness 0.15)
				)
				(justify mirror)
			)
		)
		(sheetname "/X710-AT2 10GbE/")
		(sheetfile "x710-at2-10gbe.kicad_sch")
		(attr smd)
		(fp_rect
			(start -0.925 0.47)
			(end 0.925 -0.47)
			(stroke
				(width 0.05)
				(type default)
			)
			(fill no)
			(layer "B.CrtYd")
		)
		(fp_rect
			(start -0.5 0.25)
			(end 0.5 -0.25)
			(stroke
				(width 0.15)
				(type solid)
			)
			(fill no)
			(layer "B.Fab")
		)
		(pad "1" smd roundrect
			(at -0.48 0)
			(size 0.59 0.64)
			(layers "B.Cu" "B.Mask" "B.Paste")
			(roundrect_rratio 0.25)
			(net 103 "/X710-AT2 10GbE/MDIO1_SDA1")
			(pintype "passive")
		)
		(pad "2" smd roundrect
			(at 0.48 0)
			(size 0.59 0.64)
			(layers "B.Cu" "B.Mask" "B.Paste")
			(roundrect_rratio 0.25)
			(net 7 "+3V3")
			(pintype "passive")
		)
	)
	(footprint "antmicro-footprints:TP_SMD_0.75mm"
		(layer "B.Cu")
		(at 103.55 102.7 90)
		(property "Reference" "TP3"
			(at 0.432018 0.625533 180)
			(layer "B.SilkS")
			(effects
				(font
					(size 0.7 0.7)
					(thickness 0.15)
				)
				(justify right top mirror)
			)
		)
		(property "Value" "TP_0.75mm_SMD"
			(at 0 -1.2 90)
			(layer "B.Fab")
			(hide yes)
			(effects
				(font
					(size 0.7 0.7)
					(thickness 0.15)
				)
				(justify right top mirror)
			)
		)
		(property "Description" "SMT test point"
			(at 0 0 90)
			(layer "B.Fab")
			(hide yes)
			(effects
				(font
					(size 1.27 1.27)
					(thickness 0.15)
				)
				(justify mirror)
			)
		)
		(property "MPN" ""
			(at 0 0 90)
			(unlocked yes)
			(layer "B.Fab")
			(hide yes)
			(effects
				(font
					(size 1 1)
					(thickness 0.15)
				)
				(justify mirror)
			)
		)
		(property "Manufacturer" ""
			(at 0 0 90)
			(unlocked yes)
			(layer "B.Fab")
			(hide yes)
			(effects
				(font
					(size 1 1)
					(thickness 0.15)
				)
				(justify mirror)
			)
		)
		(property "Author" "Antmicro"
			(at 0 0 90)
			(unlocked yes)
			(layer "B.Fab")
			(hide yes)
			(effects
				(font
					(size 1 1)
					(thickness 0.15)
				)
				(justify mirror)
			)
		)
		(property "License" "Apache-2.0"
			(at 0 0 90)
			(unlocked yes)
			(layer "B.Fab")
			(hide yes)
			(effects
				(font
					(size 1 1)
					(thickness 0.15)
				)
				(justify mirror)
			)
		)
		(sheetname "/X710-AT2 Misc/")
		(sheetfile "x710-at2-mics.kicad_sch")
		(attr exclude_from_pos_files exclude_from_bom)
		(fp_circle
			(center 0 0)
			(end 0.475 0)
			(stroke
				(width 0.05)
				(type default)
			)
			(fill no)
			(layer "B.CrtYd")
		)
		(pad "1" smd circle
			(at 0 0 90)
			(size 0.75 0.75)
			(layers "B.Cu" "B.Mask")
			(net 367 "/X710-AT2 Misc/NCSI.REF_CLK")
			(pinfunction "1")
			(pintype "passive")
		)
	)
	(footprint "antmicro-footprints:R_0402_1005Metric"
		(layer "B.Cu")
		(at 111.49 88.86 90)
		(descr "Resistor SMD 0402")
		(tags "resistor SMD 0402")
		(property "Reference" "R132"
			(at -3.58 -0.38 90)
			(layer "B.SilkS")
			(effects
				(font
					(size 0.7 0.7)
					(thickness 0.15)
				)
				(justify right top mirror)
			)
		)
		(property "Value" "R_10k_0402"
			(at -1.011843 -1.772046 90)
			(layer "B.Fab")
			(hide yes)
			(effects
				(font
					(size 0.7 0.7)
					(thickness 0.15)
				)
				(justify right top mirror)
			)
		)
		(property "Datasheet" "https://www.bourns.com/docs/product-datasheets/cr.pdf"
			(at 0 0 90)
			(layer "B.Fab")
			(hide yes)
			(effects
				(font
					(size 1.27 1.27)
					(thickness 0.15)
				)
				(justify mirror)
			)
		)
		(property "Description" "SMD Chip Resistor, 10 kohm, ± 1%, 62.5 mW, 0402 [1005 Metric], Thick Film, General Purpose"
			(at 0 0 90)
			(layer "B.Fab")
			(hide yes)
			(effects
				(font
					(size 1.27 1.27)
					(thickness 0.15)
				)
				(justify mirror)
			)
		)
		(property "MPN" "CR0402-FX-1002GLF"
			(at 0 0 90)
			(unlocked yes)
			(layer "B.Fab")
			(hide yes)
			(effects
				(font
					(size 1 1)
					(thickness 0.15)
				)
				(justify mirror)
			)
		)
		(property "Manufacturer" "Bourns"
			(at 0 0 90)
			(unlocked yes)
			(layer "B.Fab")
			(hide yes)
			(effects
				(font
					(size 1 1)
					(thickness 0.15)
				)
				(justify mirror)
			)
		)
		(property "License" "Apache-2.0"
			(at 0 0 90)
			(unlocked yes)
			(layer "B.Fab")
			(hide yes)
			(effects
				(font
					(size 1 1)
					(thickness 0.15)
				)
				(justify mirror)
			)
		)
		(property "Author" "Antmicro"
			(at 0 0 90)
			(unlocked yes)
			(layer "B.Fab")
			(hide yes)
			(effects
				(font
					(size 1 1)
					(thickness 0.15)
				)
				(justify mirror)
			)
		)
		(property "Val" "10k"
			(at 0 0 90)
			(unlocked yes)
			(layer "B.Fab")
			(hide yes)
			(effects
				(font
					(size 1 1)
					(thickness 0.15)
				)
				(justify mirror)
			)
		)
		(property "Tolerance" "1%"
			(at 0 0 90)
			(unlocked yes)
			(layer "B.Fab")
			(hide yes)
			(effects
				(font
					(size 1 1)
					(thickness 0.15)
				)
				(justify mirror)
			)
		)
		(sheetname "/X710-AT2 RSVD/")
		(sheetfile "x710-at2-rsvd.kicad_sch")
		(attr smd)
		(fp_rect
			(start -0.925 0.47)
			(end 0.925 -0.47)
			(stroke
				(width 0.05)
				(type default)
			)
			(fill no)
			(layer "B.CrtYd")
		)
		(fp_rect
			(start -0.5 0.25)
			(end 0.5 -0.25)
			(stroke
				(width 0.15)
				(type solid)
			)
			(fill no)
			(layer "B.Fab")
		)
		(pad "1" smd roundrect
			(at -0.48 0 90)
			(size 0.59 0.64)
			(layers "B.Cu" "B.Mask" "B.Paste")
			(roundrect_rratio 0.25)
			(net 28 "GND")
			(pintype "passive")
		)
		(pad "2" smd roundrect
			(at 0.48 0 90)
			(size 0.59 0.64)
			(layers "B.Cu" "B.Mask" "B.Paste")
			(roundrect_rratio 0.25)
			(net 120 "/X710-AT2 RSVD/DEBUG_W7")
			(pintype "passive")
		)
	)
	(footprint "antmicro-footprints:C_0402_1005Metric"
		(layer "B.Cu")
		(at 79.58 108.93 120)
		(descr "Capacitor SMD 0402")
		(tags "capacitor SMD 0402")
		(property "Reference" "C166"
			(at -7.920805 -5.600763 120)
			(layer "B.SilkS")
			(effects
				(font
					(size 0.7 0.7)
					(thickness 0.15)
				)
				(justify right top mirror)
			)
		)
		(property "Value" "C_1u_25V_0402"
			(at -1.022927 -2.155212 120)
			(layer "B.Fab")
			(hide yes)
			(effects
				(font
					(size 0.7 0.7)
					(thickness 0.15)
				)
				(justify right top mirror)
			)
		)
		(property "Datasheet" "https://www.murata.com/products/productdetail?partno=GRM155R61E105KE11%23"
			(at 0 0 120)
			(layer "B.Fab")
			(hide yes)
			(effects
				(font
					(size 1.27 1.27)
					(thickness 0.15)
				)
				(justify mirror)
			)
		)
		(property "Description" "SMD Multilayer Ceramic Capacitor, 1 µF, 25 V, 0402 [1005 Metric], ± 10%, X5R, GRM Series"
			(at 0 0 120)
			(layer "B.Fab")
			(hide yes)
			(effects
				(font
					(size 1.27 1.27)
					(thickness 0.15)
				)
				(justify mirror)
			)
		)
		(property "MPN" "GRM155R61E105KE11J"
			(at 0 0 120)
			(unlocked yes)
			(layer "B.Fab")
			(hide yes)
			(effects
				(font
					(size 1 1)
					(thickness 0.15)
				)
				(justify mirror)
			)
		)
		(property "Manufacturer" "Murata"
			(at 0 0 120)
			(unlocked yes)
			(layer "B.Fab")
			(hide yes)
			(effects
				(font
					(size 1 1)
					(thickness 0.15)
				)
				(justify mirror)
			)
		)
		(property "License" "Apache-2.0"
			(at 0 0 120)
			(unlocked yes)
			(layer "B.Fab")
			(hide yes)
			(effects
				(font
					(size 1 1)
					(thickness 0.15)
				)
				(justify mirror)
			)
		)
		(property "Author" "Antmicro"
			(at 0 0 120)
			(unlocked yes)
			(layer "B.Fab")
			(hide yes)
			(effects
				(font
					(size 1 1)
					(thickness 0.15)
				)
				(justify mirror)
			)
		)
		(property "Val" "1u"
			(at 0 0 120)
			(unlocked yes)
			(layer "B.Fab")
			(hide yes)
			(effects
				(font
					(size 1 1)
					(thickness 0.15)
				)
				(justify mirror)
			)
		)
		(property "Voltage" "25V"
			(at 0 0 120)
			(unlocked yes)
			(layer "B.Fab")
			(hide yes)
			(effects
				(font
					(size 1 1)
					(thickness 0.15)
				)
				(justify mirror)
			)
		)
		(property "Dielectric" "X5R"
			(at 0 0 120)
			(unlocked yes)
			(layer "B.Fab")
			(hide yes)
			(effects
				(font
					(size 1 1)
					(thickness 0.15)
				)
				(justify mirror)
			)
		)
		(sheetname "/X710-AT2 power/")
		(sheetfile "x710-at2-power.kicad_sch")
		(attr smd)
		(fp_poly
			(pts
				(xy -0.925 0.47) (xy 0.925 0.47) (xy 0.925 -0.47) (xy -0.925 -0.47)
			)
			(stroke
				(width 0.05)
				(type default)
			)
			(fill no)
			(layer "B.CrtYd")
		)
		(fp_line
			(start 0.504 -0.248)
			(end -0.494001 -0.248)
			(stroke
				(width 0.15)
				(type solid)
			)
			(layer "B.Fab")
		)
		(fp_line
			(start 0.504 0.25)
			(end 0.504 -0.248)
			(stroke
				(width 0.15)
				(type solid)
			)
			(layer "B.Fab")
		)
		(fp_line
			(start -0.494001 -0.248)
			(end -0.494 0.249999)
			(stroke
				(width 0.15)
				(type solid)
			)
			(layer "B.Fab")
		)
		(fp_line
			(start -0.494 0.249999)
			(end 0.504 0.25)
			(stroke
				(width 0.15)
				(type solid)
			)
			(layer "B.Fab")
		)
		(pad "1" smd roundrect
			(at -0.48 0 120)
			(size 0.59 0.64)
			(layers "B.Cu" "B.Mask" "B.Paste")
			(roundrect_rratio 0.25)
			(net 28 "GND")
			(pintype "passive")
		)
		(pad "2" smd roundrect
			(at 0.48 0 120)
			(size 0.59 0.64)
			(layers "B.Cu" "B.Mask" "B.Paste")
			(roundrect_rratio 0.25)
			(net 5 "P0_AVDDL")
			(pintype "passive")
		)
	)
	(footprint "antmicro-footprints:C_0805_2012Metric"
		(layer "B.Cu")
		(at 66 134.7)
		(descr "Capacitor SMD 0805")
		(tags "capacitor SMD 0805")
		(property "Reference" "C55"
			(at -1 1.05 0)
			(layer "B.SilkS")
			(effects
				(font
					(size 0.7 0.7)
					(thickness 0.15)
				)
				(justify right top mirror)
			)
		)
		(property "Value" "C_100u_0805"
			(at -2.055717 -1.963153 0)
			(layer "B.Fab")
			(hide yes)
			(effects
				(font
					(size 0.7 0.7)
					(thickness 0.15)
				)
				(justify right top mirror)
			)
		)
		(property "Datasheet" "https://www.murata.com/products/productdetail?partno=GRM21BR60J107ME15%23"
			(at 0 0 0)
			(layer "B.Fab")
			(hide yes)
			(effects
				(font
					(size 1.27 1.27)
					(thickness 0.15)
				)
				(justify mirror)
			)
		)
		(property "Description" "SMD Multilayer Ceramic Capacitor, 100 µF, 6.3 V, 0805 [2012 Metric], ± 20%, X5R, GRM Series"
			(at 0 0 0)
			(layer "B.Fab")
			(hide yes)
			(effects
				(font
					(size 1.27 1.27)
					(thickness 0.15)
				)
				(justify mirror)
			)
		)
		(property "MPN" "GRM21BR60J107ME15L"
			(at 0 0 0)
			(unlocked yes)
			(layer "B.Fab")
			(hide yes)
			(effects
				(font
					(size 1 1)
					(thickness 0.15)
				)
				(justify mirror)
			)
		)
		(property "Manufacturer" "Murata"
			(at 0 0 0)
			(unlocked yes)
			(layer "B.Fab")
			(hide yes)
			(effects
				(font
					(size 1 1)
					(thickness 0.15)
				)
				(justify mirror)
			)
		)
		(property "License" "Apache-2.0"
			(at 0 0 0)
			(unlocked yes)
			(layer "B.Fab")
			(hide yes)
			(effects
				(font
					(size 1 1)
					(thickness 0.15)
				)
				(justify mirror)
			)
		)
		(property "Author" "Antmicro"
			(at 0 0 0)
			(unlocked yes)
			(layer "B.Fab")
			(hide yes)
			(effects
				(font
					(size 1 1)
					(thickness 0.15)
				)
				(justify mirror)
			)
		)
		(property "Val" "100u"
			(at 0 0 0)
			(unlocked yes)
			(layer "B.Fab")
			(hide yes)
			(effects
				(font
					(size 1 1)
					(thickness 0.15)
				)
				(justify mirror)
			)
		)
		(property "Voltage" ""
			(at 0 0 0)
			(unlocked yes)
			(layer "B.Fab")
			(hide yes)
			(effects
				(font
					(size 1 1)
					(thickness 0.15)
				)
				(justify mirror)
			)
		)
		(property "Dielectric" ""
			(at 0 0 0)
			(unlocked yes)
			(layer "B.Fab")
			(hide yes)
			(effects
				(font
					(size 1 1)
					(thickness 0.15)
				)
				(justify mirror)
			)
		)
		(property "Public" "False"
			(at 0 0 0)
			(unlocked yes)
			(layer "B.Fab")
			(hide yes)
			(effects
				(font
					(size 1 1)
					(thickness 0.15)
				)
				(justify mirror)
			)
		)
		(sheetname "/2xRJ45/")
		(sheetfile "2xrj45.kicad_sch")
		(attr smd)
		(fp_line
			(start -0.3 -0.7)
			(end 0.3 -0.7)
			(stroke
				(width 0.15)
				(type solid)
			)
			(layer "B.SilkS")
		)
		(fp_line
			(start -0.3 0.7)
			(end 0.3 0.7)
			(stroke
				(width 0.15)
				(type solid)
			)
			(layer "B.SilkS")
		)
		(fp_rect
			(start 1.95 0.9)
			(end -1.95 -0.9)
			(stroke
				(width 0.05)
				(type default)
			)
			(fill no)
			(layer "B.CrtYd")
		)
		(fp_rect
			(start -0.95 0.675)
			(end 0.95 -0.675)
			(stroke
				(width 0.15)
				(type solid)
			)
			(fill no)
			(layer "B.Fab")
		)
		(pad "1" smd roundrect
			(at -1.1 0)
			(size 1.2 1.3)
			(layers "B.Cu" "B.Mask" "B.Paste")
			(roundrect_rratio 0.25)
			(net 28 "GND")
			(pintype "passive")
		)
		(pad "2" smd roundrect
			(at 1.1 0)
			(size 1.2 1.3)
			(layers "B.Cu" "B.Mask" "B.Paste")
			(roundrect_rratio 0.25)
			(net 299 "/2xRJ45/P0_CT")
			(pintype "passive")
		)
	)
)
